(kicad_pcb
	(version 20260206)
	(generator "pcbnew")
	(generator_version "10.0")
	(general
		(thickness 1.6)
		(legacy_teardrops no)
	)
	(paper "A4")
	(title_block
		(title "baseboard — 13948-1b.1110WZS1818.brd")
		(comment 1 "Honey Badger (Wiwynn) / footprints 2213-2221 of 2523")
	)
	(layers
		(0 "F.Cu" signal "TOP")
		(4 "In1.Cu" signal "L2GND")
		(6 "In2.Cu" signal "L3")
		(8 "In3.Cu" signal "L4VCC")
		(10 "In4.Cu" signal "L5VCC")
		(12 "In5.Cu" signal "L6")
		(14 "In6.Cu" signal "L7GND")
		(2 "B.Cu" signal "BOTTOM")
		(9 "F.Adhes" user "F.Adhesive")
		(11 "B.Adhes" user "B.Adhesive")
		(13 "F.Paste" user "Package Geometry/Pastemask Top")
		(15 "B.Paste" user "Package Geometry/Pastemask Bottom")
		(5 "F.SilkS" user "Ref Des/Silkscreen Top")
		(7 "B.SilkS" user "Ref Des/Silkscreen Bottom")
		(1 "F.Mask" user "Board Geometry/Soldermask Top")
		(3 "B.Mask" user "Board Geometry/Soldermask Bottom")
		(17 "Dwgs.User" user "User.Drawings")
		(19 "Cmts.User" user "User.Comments")
		(21 "Eco1.User" user "User.Eco1")
		(23 "Eco2.User" user "User.Eco2")
		(25 "Edge.Cuts" user "Board Geometry/Outline")
		(27 "Margin" user)
		(31 "F.CrtYd" user "Package Geometry/Place Bound Top")
		(29 "B.CrtYd" user "Package Geometry/Place Bound Bottom")
		(35 "F.Fab" user "Ref Des/Assembly Top")
		(33 "B.Fab" user "Ref Des/Assembly Bottom")
	)
	(footprint ""
		(layer "B.Cu")
		(at 92.056966 -35.433 -90)
		(property "Reference" "SC960"
			(at 0 0 90)
			(layer "B.SilkS")
			(hide yes)
			(effects
				(font
					(size 1.27 1.27)
				)
				(justify mirror)
			)
		)
		(property "Value" "SCD1U6D3V1KX-GP"
			(at 2.8321 -1.7399 270)
			(unlocked yes)
			(layer "B.Fab")
			(hide yes)
			(effects
				(font
					(size 1.016 1.016)
					(thickness 0.1524)
				)
				(justify mirror)
			)
		)
		(property "Device Type" "C0201H13"
			(at 2.8321 -3.2639 270)
			(unlocked yes)
			(layer "B.Fab")
			(hide yes)
			(effects
				(font
					(size 1.016 1.016)
					(thickness 0.1524)
				)
				(justify mirror)
			)
		)
		(duplicate_pad_numbers_are_jumpers no)
		(fp_rect
			(start 0.2794 0.6477)
			(end -0.2794 -0.6477)
			(stroke
				(width 0)
				(type default)
			)
			(fill no)
			(layer "B.CrtYd")
		)
		(fp_rect
			(start 0.2794 0.6477)
			(end -0.2794 -0.6477)
			(stroke
				(width 0)
				(type default)
			)
			(fill no)
			(layer "B.Fab")
		)
		(pad "1" smd custom
			(at 0 -0.2794 90)
			(size 0.0762 0.0762)
			(layers "B.Cu" "B.Mask" "B.Paste")
			(net "SAS0_AVDD")
			(options
				(clearance outline)
				(anchor circle)
			)
			(primitives
				(gr_poly
					(pts
						(arc
							(start 0.1524 0.127)
							(mid 0.137521 0.162921)
							(end 0.1016 0.1778)
						)
						(arc
							(start -0.1016 0.1778)
							(mid -0.137521 0.162921)
							(end -0.1524 0.127)
						)
						(arc
							(start -0.1524 -0.127)
							(mid -0.137521 -0.162921)
							(end -0.1016 -0.1778)
						)
						(arc
							(start 0.1016 -0.1778)
							(mid 0.137521 -0.162921)
							(end 0.1524 -0.127)
						)
					)
					(width 0)
					(fill yes)
				)
			)
		)
		(pad "2" smd custom
			(at 0 0.2794 90)
			(size 0.0762 0.0762)
			(layers "B.Cu" "B.Mask" "B.Paste")
			(net "GND")
			(options
				(clearance outline)
				(anchor circle)
			)
			(primitives
				(gr_poly
					(pts
						(arc
							(start 0.1524 0.127)
							(mid 0.137521 0.162921)
							(end 0.1016 0.1778)
						)
						(arc
							(start -0.1016 0.1778)
							(mid -0.137521 0.162921)
							(end -0.1524 0.127)
						)
						(arc
							(start -0.1524 -0.127)
							(mid -0.137521 -0.162921)
							(end -0.1016 -0.1778)
						)
						(arc
							(start 0.1016 -0.1778)
							(mid 0.137521 -0.162921)
							(end 0.1524 -0.127)
						)
					)
					(width 0)
					(fill yes)
				)
			)
		)
	)
	(footprint ""
		(layer "B.Cu")
		(at 120.96877 -79.9084 90)
		(property "Reference" "SC1151"
			(at 0 0 90)
			(layer "B.SilkS")
			(hide yes)
			(effects
				(font
					(size 1.27 1.27)
				)
				(justify mirror)
			)
		)
		(property "Value" "SC10U6D3V5KX-4GP"
			(at 0.0762 -6.1214 90)
			(unlocked yes)
			(layer "B.Fab")
			(hide yes)
			(effects
				(font
					(size 1.016 1.016)
					(thickness 0.1524)
				)
				(justify mirror)
			)
		)
		(property "Device Type" "C805H58"
			(at 0.0762 -8.1534 90)
			(unlocked yes)
			(layer "B.Fab")
			(hide yes)
			(effects
				(font
					(size 1.016 1.016)
					(thickness 0.1524)
				)
				(justify mirror)
			)
		)
		(duplicate_pad_numbers_are_jumpers no)
		(fp_line
			(start -0.635 0)
			(end 0.635 0)
			(stroke
				(width 0.508)
				(type default)
			)
			(layer "B.SilkS")
		)
		(fp_rect
			(start 0.9652 1.778)
			(end -0.9652 -1.778)
			(stroke
				(width 0)
				(type default)
			)
			(fill no)
			(layer "B.CrtYd")
		)
		(fp_poly
			(pts
				(xy 0.9652 -1.778) (xy -0.9652 -1.778) (xy -0.9652 1.778) (xy 0.9652 1.778)
			)
			(stroke
				(width 0)
				(type default)
			)
			(fill no)
			(layer "B.Fab")
		)
		(pad "1" smd rect
			(at 0 -0.9652 270)
			(size 1.397 1.143)
			(layers "B.Cu" "B.Mask" "B.Paste")
			(net "XTAL_VDDA18")
		)
		(pad "2" smd rect
			(at 0 0.9652 270)
			(size 1.397 1.143)
			(layers "B.Cu" "B.Mask" "B.Paste")
			(net "GND")
		)
	)
	(footprint ""
		(layer "B.Cu")
		(at 47.82693 -80.063086)
		(property "Reference" "TP147"
			(at 0 0 0)
			(layer "B.SilkS")
			(hide yes)
			(effects
				(font
					(size 1.27 1.27)
				)
				(justify mirror)
			)
		)
		(property "Value" "TPAD32-GP"
			(at 0 -3.166364 0)
			(unlocked yes)
			(layer "B.Fab")
			(hide yes)
			(effects
				(font
					(size 1.016 1.016)
					(thickness 0.1524)
				)
				(justify mirror)
			)
		)
		(property "Device Type" "TPAD32"
			(at 0 -4.690618 0)
			(unlocked yes)
			(layer "B.Fab")
			(hide yes)
			(effects
				(font
					(size 1.016 1.016)
					(thickness 0.1524)
				)
				(justify mirror)
			)
		)
		(duplicate_pad_numbers_are_jumpers no)
		(fp_poly
			(pts
				(arc
					(start 0.4064 0)
					(mid -0.4064 0)
					(end 0.4064 0)
				)
			)
			(stroke
				(width 0)
				(type default)
			)
			(fill no)
			(layer "B.CrtYd")
		)
		(fp_poly
			(pts
				(arc
					(start 0.7112 0)
					(mid -0.7112 0)
					(end 0.7112 0)
				)
			)
			(stroke
				(width 0)
				(type default)
			)
			(fill no)
			(layer "B.Fab")
		)
		(pad "1" smd circle
			(at 0 0 180)
			(size 0.8128 0.8128)
			(layers "B.Cu" "B.Mask" "B.Paste")
			(net "INT_CONN_A_SB1")
		)
	)
	(footprint ""
		(layer "B.Cu")
		(at 20.135088 -185.421016 90)
		(property "Reference" "SC547"
			(at 0 0 90)
			(layer "B.SilkS")
			(hide yes)
			(effects
				(font
					(size 1.27 1.27)
				)
				(justify mirror)
			)
		)
		(property "Value" "SCD1U16V2KX-3GP"
			(at -1.1811 -2.7051 90)
			(unlocked yes)
			(layer "B.Fab")
			(hide yes)
			(effects
				(font
					(size 1.016 1.016)
					(thickness 0.1524)
				)
				(justify mirror)
			)
		)
		(property "Device Type" "C402H22"
			(at -1.1811 -4.2291 90)
			(unlocked yes)
			(layer "B.Fab")
			(hide yes)
			(effects
				(font
					(size 1.016 1.016)
					(thickness 0.1524)
				)
				(justify mirror)
			)
		)
		(duplicate_pad_numbers_are_jumpers no)
		(fp_rect
			(start 0.4318 0.9525)
			(end -0.4318 -0.9525)
			(stroke
				(width 0)
				(type default)
			)
			(fill no)
			(layer "B.CrtYd")
		)
		(fp_rect
			(start 0.4318 0.9525)
			(end -0.4318 -0.9525)
			(stroke
				(width 0)
				(type default)
			)
			(fill no)
			(layer "B.Fab")
		)
		(pad "1" smd custom
			(at 0 -0.4445 270)
			(size 0.1524 0.1524)
			(layers "B.Cu" "B.Mask" "B.Paste")
			(net "P3V3_STBY")
			(options
				(clearance outline)
				(anchor circle)
			)
			(primitives
				(gr_poly
					(pts
						(arc
							(start 0.3048 0.2032)
							(mid 0.275042 0.275042)
							(end 0.2032 0.3048)
						)
						(arc
							(start -0.2032 0.3048)
							(mid -0.275042 0.275042)
							(end -0.3048 0.2032)
						)
						(arc
							(start -0.3048 -0.2032)
							(mid -0.275042 -0.275042)
							(end -0.2032 -0.3048)
						)
						(arc
							(start 0.2032 -0.3048)
							(mid 0.275042 -0.275042)
							(end 0.3048 -0.2032)
						)
					)
					(width 0)
					(fill yes)
				)
			)
		)
		(pad "2" smd custom
			(at 0 0.4445 270)
			(size 0.1524 0.1524)
			(layers "B.Cu" "B.Mask" "B.Paste")
			(net "GND")
			(options
				(clearance outline)
				(anchor circle)
			)
			(primitives
				(gr_poly
					(pts
						(arc
							(start 0.3048 0.2032)
							(mid 0.275042 0.275042)
							(end 0.2032 0.3048)
						)
						(arc
							(start -0.2032 0.3048)
							(mid -0.275042 0.275042)
							(end -0.3048 0.2032)
						)
						(arc
							(start -0.3048 -0.2032)
							(mid -0.275042 -0.275042)
							(end -0.2032 -0.3048)
						)
						(arc
							(start 0.2032 -0.3048)
							(mid 0.275042 -0.275042)
							(end 0.3048 -0.2032)
						)
					)
					(width 0)
					(fill yes)
				)
			)
		)
	)
	(footprint ""
		(layer "B.Cu")
		(at 114.41557 -92.3798)
		(property "Reference" "SC1256"
			(at 0 0 0)
			(layer "B.SilkS")
			(hide yes)
			(effects
				(font
					(size 1.27 1.27)
				)
				(justify mirror)
			)
		)
		(property "Value" "SCD1U6D3V1KX-GP"
			(at 2.8321 -1.7399 0)
			(unlocked yes)
			(layer "B.Fab")
			(hide yes)
			(effects
				(font
					(size 1.016 1.016)
					(thickness 0.1524)
				)
				(justify mirror)
			)
		)
		(property "Device Type" "C0201H13"
			(at 2.8321 -3.2639 0)
			(unlocked yes)
			(layer "B.Fab")
			(hide yes)
			(effects
				(font
					(size 1.016 1.016)
					(thickness 0.1524)
				)
				(justify mirror)
			)
		)
		(duplicate_pad_numbers_are_jumpers no)
		(fp_rect
			(start 0.2794 0.6477)
			(end -0.2794 -0.6477)
			(stroke
				(width 0)
				(type default)
			)
			(fill no)
			(layer "B.CrtYd")
		)
		(fp_rect
			(start 0.2794 0.6477)
			(end -0.2794 -0.6477)
			(stroke
				(width 0)
				(type default)
			)
			(fill no)
			(layer "B.Fab")
		)
		(pad "1" smd custom
			(at 0 -0.2794 180)
			(size 0.0762 0.0762)
			(layers "B.Cu" "B.Mask" "B.Paste")
			(net "P0V9_E")
			(options
				(clearance outline)
				(anchor circle)
			)
			(primitives
				(gr_poly
					(pts
						(arc
							(start 0.1524 0.127)
							(mid 0.137521 0.162921)
							(end 0.1016 0.1778)
						)
						(arc
							(start -0.1016 0.1778)
							(mid -0.137521 0.162921)
							(end -0.1524 0.127)
						)
						(arc
							(start -0.1524 -0.127)
							(mid -0.137521 -0.162921)
							(end -0.1016 -0.1778)
						)
						(arc
							(start 0.1016 -0.1778)
							(mid 0.137521 -0.162921)
							(end 0.1524 -0.127)
						)
					)
					(width 0)
					(fill yes)
				)
			)
		)
		(pad "2" smd custom
			(at 0 0.2794 180)
			(size 0.0762 0.0762)
			(layers "B.Cu" "B.Mask" "B.Paste")
			(net "GND")
			(options
				(clearance outline)
				(anchor circle)
			)
			(primitives
				(gr_poly
					(pts
						(arc
							(start 0.1524 0.127)
							(mid 0.137521 0.162921)
							(end 0.1016 0.1778)
						)
						(arc
							(start -0.1016 0.1778)
							(mid -0.137521 0.162921)
							(end -0.1524 0.127)
						)
						(arc
							(start -0.1524 -0.127)
							(mid -0.137521 -0.162921)
							(end -0.1016 -0.1778)
						)
						(arc
							(start 0.1016 -0.1778)
							(mid 0.137521 -0.162921)
							(end 0.1524 -0.127)
						)
					)
					(width 0)
					(fill yes)
				)
			)
		)
	)
	(footprint ""
		(layer "B.Cu")
		(at 109.671612 -204.978 180)
		(property "Reference" "SR895"
			(at 0 0 0)
			(layer "B.SilkS")
			(hide yes)
			(effects
				(font
					(size 1.27 1.27)
				)
				(justify mirror)
			)
		)
		(property "Value" "0R2J-2-GP"
			(at -0.064008 -3.993896 180)
			(unlocked yes)
			(layer "B.Fab")
			(hide yes)
			(effects
				(font
					(size 1.016 1.016)
					(thickness 0.1524)
				)
				(justify mirror)
			)
		)
		(property "Device Type" "R402H16"
			(at -0.064008 -5.517896 180)
			(unlocked yes)
			(layer "B.Fab")
			(hide yes)
			(effects
				(font
					(size 1.016 1.016)
					(thickness 0.1524)
				)
				(justify mirror)
			)
		)
		(duplicate_pad_numbers_are_jumpers no)
		(fp_line
			(start 0.508 -0.9398)
			(end 0.508 0.9398)
			(stroke
				(width 0.1524)
				(type default)
			)
			(layer "B.SilkS")
		)
		(fp_line
			(start -0.508 -0.9398)
			(end 0.508 -0.9398)
			(stroke
				(width 0.1524)
				(type default)
			)
			(layer "B.SilkS")
		)
		(fp_rect
			(start 0.508 0.9398)
			(end -0.508 -0.9398)
			(stroke
				(width 0)
				(type default)
			)
			(fill no)
			(layer "B.CrtYd")
		)
		(fp_rect
			(start 0.508 0.9398)
			(end -0.508 -0.9398)
			(stroke
				(width 0)
				(type default)
			)
			(fill no)
			(layer "B.Fab")
		)
		(pad "1" smd custom
			(at 0 -0.4445)
			(size 0.1397 0.1397)
			(layers "B.Cu" "B.Mask" "B.Paste")
			(net "REDV_RX8_P")
			(options
				(clearance outline)
				(anchor circle)
			)
			(primitives
				(gr_poly
					(pts
						(arc
							(start -0.1778 0.2794)
							(mid -0.249642 0.249642)
							(end -0.2794 0.1778)
						)
						(arc
							(start -0.2794 -0.1778)
							(mid -0.249642 -0.249642)
							(end -0.1778 -0.2794)
						)
						(arc
							(start 0.1778 -0.2794)
							(mid 0.249642 -0.249642)
							(end 0.2794 -0.1778)
						)
						(arc
							(start 0.2794 0.1778)
							(mid 0.249642 0.249642)
							(end 0.1778 0.2794)
						)
					)
					(width 0)
					(fill yes)
				)
			)
		)
		(pad "2" smd custom
			(at 0 0.4445)
			(size 0.1397 0.1397)
			(layers "B.Cu" "B.Mask" "B.Paste")
			(net "SAS_HDD_CONN_RX8_P")
			(options
				(clearance outline)
				(anchor circle)
			)
			(primitives
				(gr_poly
					(pts
						(arc
							(start -0.1778 0.2794)
							(mid -0.249642 0.249642)
							(end -0.2794 0.1778)
						)
						(arc
							(start -0.2794 -0.1778)
							(mid -0.249642 -0.249642)
							(end -0.1778 -0.2794)
						)
						(arc
							(start 0.1778 -0.2794)
							(mid 0.249642 -0.249642)
							(end 0.2794 -0.1778)
						)
						(arc
							(start 0.2794 0.1778)
							(mid 0.249642 0.249642)
							(end 0.1778 0.2794)
						)
					)
					(width 0)
					(fill yes)
				)
			)
		)
	)
	(footprint ""
		(layer "B.Cu")
		(at 262.001 -16.891 180)
		(property "Reference" "C334"
			(at 0 0 0)
			(layer "B.SilkS")
			(hide yes)
			(effects
				(font
					(size 1.27 1.27)
				)
				(justify mirror)
			)
		)
		(property "Value" "SC1U10V3KX-4GP-U"
			(at 0 -2.8194 180)
			(unlocked yes)
			(layer "B.Fab")
			(hide yes)
			(effects
				(font
					(size 1.016 1.016)
					(thickness 0.1524)
				)
				(justify mirror)
			)
		)
		(property "Device Type" "C603H36"
			(at 0 -4.3434 180)
			(unlocked yes)
			(layer "B.Fab")
			(hide yes)
			(effects
				(font
					(size 1.016 1.016)
					(thickness 0.1524)
				)
				(justify mirror)
			)
		)
		(duplicate_pad_numbers_are_jumpers no)
		(fp_line
			(start -0.508 0)
			(end 0.508 0)
			(stroke
				(width 0.2032)
				(type default)
			)
			(layer "B.SilkS")
		)
		(fp_rect
			(start 0.5842 1.3335)
			(end -0.5842 -1.3335)
			(stroke
				(width 0)
				(type default)
			)
			(fill no)
			(layer "B.CrtYd")
		)
		(fp_rect
			(start 0.5842 1.3335)
			(end -0.5842 -1.3335)
			(stroke
				(width 0)
				(type default)
			)
			(fill no)
			(layer "B.Fab")
		)
		(pad "1" smd custom
			(at 0 -0.762)
			(size 0.2159 0.2159)
			(layers "B.Cu" "B.Mask" "B.Paste")
			(net "P5V_USB")
			(options
				(clearance outline)
				(anchor circle)
			)
			(primitives
				(gr_poly
					(pts
						(arc
							(start -0.3302 0.4318)
							(mid -0.402042 0.402042)
							(end -0.4318 0.3302)
						)
						(arc
							(start -0.4318 -0.3302)
							(mid -0.402042 -0.402042)
							(end -0.3302 -0.4318)
						)
						(arc
							(start 0.3302 -0.4318)
							(mid 0.402042 -0.402042)
							(end 0.4318 -0.3302)
						)
						(arc
							(start 0.4318 0.3302)
							(mid 0.402042 0.402042)
							(end 0.3302 0.4318)
						)
					)
					(width 0)
					(fill yes)
				)
			)
		)
		(pad "2" smd custom
			(at 0 0.762)
			(size 0.2159 0.2159)
			(layers "B.Cu" "B.Mask" "B.Paste")
			(net "GND")
			(options
				(clearance outline)
				(anchor circle)
			)
			(primitives
				(gr_poly
					(pts
						(arc
							(start -0.3302 0.4318)
							(mid -0.402042 0.402042)
							(end -0.4318 0.3302)
						)
						(arc
							(start -0.4318 -0.3302)
							(mid -0.402042 -0.402042)
							(end -0.3302 -0.4318)
						)
						(arc
							(start 0.3302 -0.4318)
							(mid 0.402042 -0.402042)
							(end 0.4318 -0.3302)
						)
						(arc
							(start 0.4318 0.3302)
							(mid 0.402042 0.402042)
							(end 0.3302 0.4318)
						)
					)
					(width 0)
					(fill yes)
				)
			)
		)
	)
	(footprint ""
		(layer "B.Cu")
		(at 324.358 -177.8)
		(property "Reference" "C8088"
			(at 0 0 0)
			(layer "B.SilkS")
			(hide yes)
			(effects
				(font
					(size 1.27 1.27)
				)
				(justify mirror)
			)
		)
		(property "Value" "SCD1U25V2KX-2-GP"
			(at -1.1811 -2.7051 0)
			(unlocked yes)
			(layer "B.Fab")
			(hide yes)
			(effects
				(font
					(size 1.016 1.016)
					(thickness 0.1524)
				)
				(justify mirror)
			)
		)
		(property "Device Type" "C402H22"
			(at -1.1811 -4.2291 0)
			(unlocked yes)
			(layer "B.Fab")
			(hide yes)
			(effects
				(font
					(size 1.016 1.016)
					(thickness 0.1524)
				)
				(justify mirror)
			)
		)
		(duplicate_pad_numbers_are_jumpers no)
		(fp_rect
			(start 0.4318 0.9525)
			(end -0.4318 -0.9525)
			(stroke
				(width 0)
				(type default)
			)
			(fill no)
			(layer "B.CrtYd")
		)
		(fp_rect
			(start 0.4318 0.9525)
			(end -0.4318 -0.9525)
			(stroke
				(width 0)
				(type default)
			)
			(fill no)
			(layer "B.Fab")
		)
		(pad "1" smd custom
			(at 0 -0.4445 180)
			(size 0.1524 0.1524)
			(layers "B.Cu" "B.Mask" "B.Paste")
			(net "ADC_P5V_STBY")
			(options
				(clearance outline)
				(anchor circle)
			)
			(primitives
				(gr_poly
					(pts
						(arc
							(start 0.3048 0.2032)
							(mid 0.275042 0.275042)
							(end 0.2032 0.3048)
						)
						(arc
							(start -0.2032 0.3048)
							(mid -0.275042 0.275042)
							(end -0.3048 0.2032)
						)
						(arc
							(start -0.3048 -0.2032)
							(mid -0.275042 -0.275042)
							(end -0.2032 -0.3048)
						)
						(arc
							(start 0.2032 -0.3048)
							(mid 0.275042 -0.275042)
							(end 0.3048 -0.2032)
						)
					)
					(width 0)
					(fill yes)
				)
			)
		)
		(pad "2" smd custom
			(at 0 0.4445 180)
			(size 0.1524 0.1524)
			(layers "B.Cu" "B.Mask" "B.Paste")
			(net "GND")
			(options
				(clearance outline)
				(anchor circle)
			)
			(primitives
				(gr_poly
					(pts
						(arc
							(start 0.3048 0.2032)
							(mid 0.275042 0.275042)
							(end 0.2032 0.3048)
						)
						(arc
							(start -0.2032 0.3048)
							(mid -0.275042 0.275042)
							(end -0.3048 0.2032)
						)
						(arc
							(start -0.3048 -0.2032)
							(mid -0.275042 -0.275042)
							(end -0.2032 -0.3048)
						)
						(arc
							(start 0.2032 -0.3048)
							(mid 0.275042 -0.275042)
							(end 0.3048 -0.2032)
						)
					)
					(width 0)
					(fill yes)
				)
			)
		)
	)
	(footprint ""
		(layer "B.Cu")
		(at 68.599812 -39.399718)
		(property "Reference" ""
			(at 0 0 0)
			(layer "B.SilkS")
			(hide yes)
			(effects
				(font
					(size 1.27 1.27)
				)
				(justify mirror)
			)
		)
		(property "Value" "*"
			(at 5.5753 -0.4572 0)
			(unlocked yes)
			(layer "B.Fab")
			(hide yes)
			(effects
				(font
					(size 1.016 1.016)
					(thickness 0.1524)
				)
				(justify mirror)
			)
		)
		(duplicate_pad_numbers_are_jumpers no)
		(fp_poly
			(pts
				(arc
					(start 4.3053 0)
					(mid -4.3053 0)
					(end 4.3053 0)
				)
			)
			(stroke
				(width 0)
				(type default)
			)
			(fill no)
			(layer "B.CrtYd")
		)
		(fp_poly
			(pts
				(arc
					(start 4.3053 0)
					(mid -4.3053 0)
					(end 4.3053 0)
				)
			)
			(stroke
				(width 0)
				(type default)
			)
			(fill no)
			(layer "B.Fab")
		)
		(pad "1" smd custom
			(at 2.95275 0 180)
			(size 2.000013 2.000013)
			(layers "B.Cu" "B.Mask" "B.Paste")
			(net "Net_56")
			(options
				(clearance outline)
				(anchor circle)
			)
			(primitives
				(gr_poly
					(pts
						(arc
							(start 4.0005 -0.00254)
							(mid -4.000501 0)
							(end 4.0005 0.00254)
						)
						(arc
							(start 1.905 0.00254)
							(mid -1.905002 0)
							(end 1.905 -0.00254)
						)
					)
					(width 0)
					(fill yes)
				)
			)
		)
	)
)
